(kicad_pcb
	(version 20241229)
	(generator "pcbnew")
	(generator_version "9.0")
	(general
		(thickness 1.6296)
		(legacy_teardrops no)
	)
	(paper "A3")
	(title_block
		(title "Thunderbolt to 10GbE adapter")
		(date "2026-04-21")
		(rev "1.1.0")
		(company "Antmicro Ltd")
		(comment 1 "www.antmicro.com")
		(comment 9 "footprints 50-53 of 703")
	)
	(layers
		(0 "F.Cu" signal)
		(4 "In1.Cu" signal)
		(6 "In2.Cu" signal)
		(8 "In3.Cu" signal)
		(10 "In4.Cu" signal)
		(12 "In5.Cu" signal)
		(14 "In6.Cu" signal)
		(2 "B.Cu" signal)
		(9 "F.Adhes" user "F.Adhesive")
		(11 "B.Adhes" user "B.Adhesive")
		(13 "F.Paste" user)
		(15 "B.Paste" user)
		(5 "F.SilkS" user "F.Silkscreen")
		(7 "B.SilkS" user "B.Silkscreen")
		(1 "F.Mask" user)
		(3 "B.Mask" user)
		(17 "Dwgs.User" user "User.Drawings")
		(19 "Cmts.User" user "User.Comments")
		(21 "Eco1.User" user "User.Eco1")
		(23 "Eco2.User" user "User.Eco2")
		(25 "Edge.Cuts" user)
		(27 "Margin" user)
		(31 "F.CrtYd" user "F.Courtyard")
		(29 "B.CrtYd" user "B.Courtyard")
		(35 "F.Fab" user)
		(33 "B.Fab" user)
	)
	(footprint "antmicro-footprints:C_Pol_EIA-B"
		(layer "F.Cu")
		(at 139.25 130.25 90)
		(property "Reference" "C53"
			(at 0.55 5.750001 90)
			(layer "F.SilkS")
			(effects
				(font
					(size 0.7 0.7)
					(thickness 0.15)
				)
				(justify left bottom)
			)
		)
		(property "Value" "C_Pol_330u_6.3V_KEMET-T520-B"
			(at 0 2.85 90)
			(layer "F.Fab")
			(effects
				(font
					(size 0.7 0.7)
					(thickness 0.15)
				)
				(justify left bottom)
			)
		)
		(property "Datasheet" "https://www.kemet.com/en/us/capacitors/product/T520B337M006ATE040.html"
			(at 0 0 90)
			(layer "F.Fab")
			(hide yes)
			(effects
				(font
					(size 1.27 1.27)
					(thickness 0.15)
				)
			)
		)
		(property "Description" "Tantalum Polymer Capacitor, KO-CAP®, 330 µF, ± 20%, 6.3 V, B, 0.04 ohm, 1411 [3528 Metric]"
			(at 0 0 90)
			(layer "F.Fab")
			(hide yes)
			(effects
				(font
					(size 1.27 1.27)
					(thickness 0.15)
				)
			)
		)
		(property "Val" "330u"
			(at 0 0 90)
			(unlocked yes)
			(layer "F.Fab")
			(hide yes)
			(effects
				(font
					(size 1 1)
					(thickness 0.15)
				)
			)
		)
		(property "MPN" "T520B337M006ATE040"
			(at 0 0 90)
			(unlocked yes)
			(layer "F.Fab")
			(hide yes)
			(effects
				(font
					(size 1 1)
					(thickness 0.15)
				)
			)
		)
		(property "Manufacturer" "KEMET"
			(at 0 0 90)
			(unlocked yes)
			(layer "F.Fab")
			(hide yes)
			(effects
				(font
					(size 1 1)
					(thickness 0.15)
				)
			)
		)
		(property "License" "Apache-2.0"
			(at 0 0 90)
			(unlocked yes)
			(layer "F.Fab")
			(hide yes)
			(effects
				(font
					(size 1 1)
					(thickness 0.15)
				)
			)
		)
		(property "Author" "Antmicro"
			(at 0 0 90)
			(unlocked yes)
			(layer "F.Fab")
			(hide yes)
			(effects
				(font
					(size 1 1)
					(thickness 0.15)
				)
			)
		)
		(property "Voltage" "6.3V"
			(at 0 0 90)
			(unlocked yes)
			(layer "F.Fab")
			(hide yes)
			(effects
				(font
					(size 1 1)
					(thickness 0.15)
				)
			)
		)
		(property "Dielectric" "template_dielectric"
			(at 0 0 90)
			(unlocked yes)
			(layer "F.Fab")
			(hide yes)
			(effects
				(font
					(size 1 1)
					(thickness 0.15)
				)
			)
		)
		(sheetname "/TB Controller - Power/")
		(sheetfile "tb-power.kicad_sch")
		(attr smd)
		(fp_line
			(start -2.521 -1.676)
			(end -2.123 -1.676)
			(stroke
				(width 0.15)
				(type solid)
			)
			(layer "F.SilkS")
		)
		(fp_line
			(start -1.8 -1.6)
			(end 1.8 -1.6)
			(stroke
				(width 0.15)
				(type solid)
			)
			(layer "F.SilkS")
		)
		(fp_line
			(start -2.325 -1.475)
			(end -2.325 -1.878)
			(stroke
				(width 0.15)
				(type solid)
			)
			(layer "F.SilkS")
		)
		(fp_line
			(start 1.8 -1.3)
			(end 1.8 -1.6)
			(stroke
				(width 0.15)
				(type solid)
			)
			(layer "F.SilkS")
		)
		(fp_line
			(start -1.8 -1.3)
			(end -1.8 -1.6)
			(stroke
				(width 0.15)
				(type solid)
			)
			(layer "F.SilkS")
		)
		(fp_line
			(start 1.8 1.3)
			(end 1.8 1.6)
			(stroke
				(width 0.15)
				(type solid)
			)
			(layer "F.SilkS")
		)
		(fp_line
			(start -1.8 1.3)
			(end -1.8 1.6)
			(stroke
				(width 0.15)
				(type solid)
			)
			(layer "F.SilkS")
		)
		(fp_line
			(start 1.8 1.6)
			(end -1.8 1.6)
			(stroke
				(width 0.15)
				(type solid)
			)
			(layer "F.SilkS")
		)
		(fp_line
			(start 1.959 -1.75)
			(end -1.97 -1.75)
			(stroke
				(width 0.05)
				(type solid)
			)
			(layer "F.CrtYd")
		)
		(fp_line
			(start 1.959 -1.75)
			(end 1.959 -1.35)
			(stroke
				(width 0.05)
				(type solid)
			)
			(layer "F.CrtYd")
		)
		(fp_line
			(start -1.97 -1.75)
			(end -1.97 -1.35)
			(stroke
				(width 0.05)
				(type solid)
			)
			(layer "F.CrtYd")
		)
		(fp_line
			(start 2.399 -1.35)
			(end 1.959 -1.35)
			(stroke
				(width 0.05)
				(type solid)
			)
			(layer "F.CrtYd")
		)
		(fp_line
			(start 2.399 -1.35)
			(end 2.4 1.35)
			(stroke
				(width 0.05)
				(type solid)
			)
			(layer "F.CrtYd")
		)
		(fp_line
			(start -1.97 -1.35)
			(end -2.41 -1.35)
			(stroke
				(width 0.05)
				(type solid)
			)
			(layer "F.CrtYd")
		)
		(fp_line
			(start -2.411 -1.35)
			(end -2.41 1.35)
			(stroke
				(width 0.05)
				(type solid)
			)
			(layer "F.CrtYd")
		)
		(fp_line
			(start 2.4 1.35)
			(end 1.96 1.35)
			(stroke
				(width 0.05)
				(type solid)
			)
			(layer "F.CrtYd")
		)
		(fp_line
			(start 1.96 1.35)
			(end 1.96 1.75)
			(stroke
				(width 0.05)
				(type solid)
			)
			(layer "F.CrtYd")
		)
		(fp_line
			(start -1.97 1.35)
			(end -2.41 1.35)
			(stroke
				(width 0.05)
				(type solid)
			)
			(layer "F.CrtYd")
		)
		(fp_line
			(start -1.97 1.35)
			(end -1.97 1.75)
			(stroke
				(width 0.05)
				(type solid)
			)
			(layer "F.CrtYd")
		)
		(fp_line
			(start 1.96 1.75)
			(end -1.97 1.75)
			(stroke
				(width 0.05)
				(type solid)
			)
			(layer "F.CrtYd")
		)
		(fp_line
			(start -1.7 1.324)
			(end -1.551 1.475)
			(stroke
				(width 0.15)
				(type solid)
			)
			(layer "F.Fab")
		)
		(fp_rect
			(start -1.72 -1.5)
			(end 1.719 1.499)
			(stroke
				(width 0.15)
				(type solid)
			)
			(fill no)
			(layer "F.Fab")
		)
		(fp_text user "Author: Antmicro"
			(at -2.665 6.85 90)
			(layer "F.Fab")
			(effects
				(font
					(size 0.7 0.7)
					(thickness 0.15)
				)
				(justify left bottom)
			)
		)
		(fp_text user "License: Apache-2.0"
			(at -2.665 5.65 90)
			(layer "F.Fab")
			(effects
				(font
					(size 0.7 0.7)
					(thickness 0.15)
				)
				(justify left bottom)
			)
		)
		(fp_text user "${REFERENCE}"
			(at -2.665 4.45 90)
			(layer "F.Fab")
			(effects
				(font
					(size 0.7 0.7)
					(thickness 0.15)
				)
				(justify left bottom)
			)
		)
		(pad "1" smd roundrect
			(at -1.551 0 90)
			(size 1.2 2.2)
			(layers "F.Cu" "F.Mask" "F.Paste")
			(roundrect_rratio 0.1)
			(net 57 "+3V3_TB")
			(pintype "passive")
		)
		(pad "2" smd roundrect
			(at 1.55 0 90)
			(size 1.2 2.2)
			(layers "F.Cu" "F.Mask" "F.Paste")
			(roundrect_rratio 0.1)
			(net 23 "GND")
			(pintype "passive")
		)
	)
	(footprint "antmicro-footprints:SOT-23-5"
		(layer "F.Cu")
		(at 119 89)
		(property "Reference" "U6"
			(at -2 -2 0)
			(layer "F.SilkS")
			(effects
				(font
					(size 0.7 0.7)
					(thickness 0.15)
				)
				(justify left bottom)
			)
		)
		(property "Value" "MCP6541_SOT23-5"
			(at 0.002 2.799 0)
			(layer "F.Fab")
			(effects
				(font
					(size 0.7 0.7)
					(thickness 0.15)
				)
				(justify left bottom)
			)
		)
		(property "Datasheet" "https://www.farnell.com/datasheets/1641674.pdf"
			(at 0 0 0)
			(layer "F.Fab")
			(hide yes)
			(effects
				(font
					(size 1.27 1.27)
					(thickness 0.15)
				)
			)
		)
		(property "Description" "Push-Pull Output Comparator, 1,6V to 5.5V, SOT-23-5"
			(at 0 0 0)
			(layer "F.Fab")
			(hide yes)
			(effects
				(font
					(size 1.27 1.27)
					(thickness 0.15)
				)
			)
		)
		(property "MPN" "MCP6541T-E/OT"
			(at 0 0 0)
			(unlocked yes)
			(layer "F.Fab")
			(hide yes)
			(effects
				(font
					(size 1 1)
					(thickness 0.15)
				)
			)
		)
		(property "Manufacturer" "Microchip Technology"
			(at 0 0 0)
			(unlocked yes)
			(layer "F.Fab")
			(hide yes)
			(effects
				(font
					(size 1 1)
					(thickness 0.15)
				)
			)
		)
		(property "Author" "Antmicro"
			(at 0 0 0)
			(unlocked yes)
			(layer "F.Fab")
			(hide yes)
			(effects
				(font
					(size 1 1)
					(thickness 0.15)
				)
			)
		)
		(property "License" "Apache-2.0"
			(at 0 0 0)
			(unlocked yes)
			(layer "F.Fab")
			(hide yes)
			(effects
				(font
					(size 1 1)
					(thickness 0.15)
				)
			)
		)
		(sheetname "/TB Controller - Power/")
		(sheetfile "tb-power.kicad_sch")
		(attr smd)
		(fp_line
			(start -0.85 1.6)
			(end -0.85 1.301)
			(stroke
				(width 0.15)
				(type solid)
			)
			(layer "F.SilkS")
		)
		(fp_line
			(start -0.8 -1.6)
			(end -0.8 -1.3)
			(stroke
				(width 0.15)
				(type solid)
			)
			(layer "F.SilkS")
		)
		(fp_line
			(start -0.8 -1.6)
			(end -0.5 -1.6)
			(stroke
				(width 0.15)
				(type solid)
			)
			(layer "F.SilkS")
		)
		(fp_line
			(start -0.55 1.6)
			(end -0.85 1.6)
			(stroke
				(width 0.15)
				(type solid)
			)
			(layer "F.SilkS")
		)
		(fp_line
			(start 0.8 -1.6)
			(end 0.5 -1.6)
			(stroke
				(width 0.15)
				(type solid)
			)
			(layer "F.SilkS")
		)
		(fp_line
			(start 0.8 -1.3)
			(end 0.8 -1.6)
			(stroke
				(width 0.15)
				(type solid)
			)
			(layer "F.SilkS")
		)
		(fp_line
			(start 0.8 0.55)
			(end 0.8 -0.55)
			(stroke
				(width 0.15)
				(type solid)
			)
			(layer "F.SilkS")
		)
		(fp_line
			(start 0.8 1.3)
			(end 0.8 1.599)
			(stroke
				(width 0.15)
				(type solid)
			)
			(layer "F.SilkS")
		)
		(fp_line
			(start 0.8 1.599)
			(end 0.549 1.599)
			(stroke
				(width 0.15)
				(type solid)
			)
			(layer "F.SilkS")
		)
		(fp_circle
			(center -1.25 -1.5)
			(end -1.2 -1.5)
			(stroke
				(width 0.15)
				(type solid)
			)
			(fill yes)
			(layer "F.SilkS")
		)
		(fp_rect
			(start 1.9 -1.76)
			(end -1.9 1.75)
			(stroke
				(width 0.05)
				(type solid)
			)
			(fill no)
			(layer "F.CrtYd")
		)
		(fp_line
			(start -0.398 -1.526)
			(end -0.874 -1.05)
			(stroke
				(width 0.15)
				(type solid)
			)
			(layer "F.Fab")
		)
		(fp_rect
			(start 0.874 1.523)
			(end -0.873 -1.525)
			(stroke
				(width 0.15)
				(type solid)
			)
			(fill no)
			(layer "F.Fab")
		)
		(fp_text user "Author: Antmicro"
			(at -1.898 5.499 0)
			(layer "F.Fab")
			(effects
				(font
					(size 0.7 0.7)
					(thickness 0.15)
				)
				(justify left bottom)
			)
		)
		(fp_text user "License: Apache-2.0"
			(at -1.898 6.7 0)
			(layer "F.Fab")
			(effects
				(font
					(size 0.7 0.7)
					(thickness 0.15)
				)
				(justify left bottom)
			)
		)
		(fp_text user "${REFERENCE}"
			(at -1.898 4.299 0)
			(layer "F.Fab")
			(effects
				(font
					(size 0.7 0.7)
					(thickness 0.15)
				)
				(justify left bottom)
			)
		)
		(pad "1" smd rect
			(at -1.351 -0.951 270)
			(size 0.55 1)
			(layers "F.Cu" "F.Mask" "F.Paste")
			(net 356 "/TB Controller - Power/0P9_BUFFERED")
			(pintype "output")
		)
		(pad "2" smd rect
			(at -1.351 0 270)
			(size 0.55 1)
			(layers "F.Cu" "F.Mask" "F.Paste")
			(net 23 "GND")
			(pinfunction "VSS")
			(pintype "power_in")
		)
		(pad "3" smd rect
			(at -1.351 0.949 270)
			(size 0.55 1)
			(layers "F.Cu" "F.Mask" "F.Paste")
			(net 436 "Net-(R77-Pad1)")
			(pintype "input")
		)
		(pad "4" smd rect
			(at 1.35 0.949 270)
			(size 0.55 1)
			(layers "F.Cu" "F.Mask" "F.Paste")
			(net 435 "Net-(R75-Pad1)")
			(pintype "input")
		)
		(pad "5" smd rect
			(at 1.35 -0.951 270)
			(size 0.55 1)
			(layers "F.Cu" "F.Mask" "F.Paste")
			(net 57 "+3V3_TB")
			(pinfunction "VDD")
			(pintype "power_in")
		)
	)
	(footprint "antmicro-footprints:R_0402_1005Metric"
		(layer "F.Cu")
		(at 165.265 60.1 90)
		(descr "Resistor SMD 0402")
		(tags "resistor SMD 0402")
		(property "Reference" "R184"
			(at 6.7 -0.065 90)
			(layer "F.SilkS")
			(effects
				(font
					(size 0.7 0.7)
					(thickness 0.15)
				)
				(justify left bottom)
			)
		)
		(property "Value" "R_10k_0402"
			(at -1.011843 1.772047 90)
			(layer "F.Fab")
			(effects
				(font
					(size 0.7 0.7)
					(thickness 0.15)
				)
				(justify left bottom)
			)
		)
		(property "Datasheet" "https://www.bourns.com/docs/product-datasheets/cr.pdf"
			(at 0 0 90)
			(layer "F.Fab")
			(hide yes)
			(effects
				(font
					(size 1.27 1.27)
					(thickness 0.15)
				)
			)
		)
		(property "Description" "SMD Chip Resistor, 10 kohm, ± 1%, 62.5 mW, 0402 [1005 Metric], Thick Film, General Purpose"
			(at 0 0 90)
			(layer "F.Fab")
			(hide yes)
			(effects
				(font
					(size 1.27 1.27)
					(thickness 0.15)
				)
			)
		)
		(property "MPN" "CR0402-FX-1002GLF"
			(at 0 0 90)
			(unlocked yes)
			(layer "F.Fab")
			(hide yes)
			(effects
				(font
					(size 1 1)
					(thickness 0.15)
				)
			)
		)
		(property "Manufacturer" "Bourns"
			(at 0 0 90)
			(unlocked yes)
			(layer "F.Fab")
			(hide yes)
			(effects
				(font
					(size 1 1)
					(thickness 0.15)
				)
			)
		)
		(property "License" "Apache-2.0"
			(at 0 0 90)
			(unlocked yes)
			(layer "F.Fab")
			(hide yes)
			(effects
				(font
					(size 1 1)
					(thickness 0.15)
				)
			)
		)
		(property "Author" "Antmicro"
			(at 0 0 90)
			(unlocked yes)
			(layer "F.Fab")
			(hide yes)
			(effects
				(font
					(size 1 1)
					(thickness 0.15)
				)
			)
		)
		(property "Val" "10k"
			(at 0 0 90)
			(unlocked yes)
			(layer "F.Fab")
			(hide yes)
			(effects
				(font
					(size 1 1)
					(thickness 0.15)
				)
			)
		)
		(property "Tolerance" "1%"
			(at 0 0 90)
			(unlocked yes)
			(layer "F.Fab")
			(hide yes)
			(effects
				(font
					(size 1 1)
					(thickness 0.15)
				)
			)
		)
		(sheetname "/X710-AT2 10GbE/")
		(sheetfile "x710-at2-10gbe.kicad_sch")
		(attr smd)
		(fp_rect
			(start -0.925 -0.47)
			(end 0.925 0.47)
			(stroke
				(width 0.05)
				(type default)
			)
			(fill no)
			(layer "F.CrtYd")
		)
		(fp_rect
			(start -0.5 -0.25)
			(end 0.5 0.25)
			(stroke
				(width 0.15)
				(type solid)
			)
			(fill no)
			(layer "F.Fab")
		)
		(fp_text user "License: Apache-2.0"
			(at -0.95 5.169 90)
			(layer "F.Fab")
			(effects
				(font
					(size 0.7 0.7)
					(thickness 0.15)
				)
				(justify left bottom)
			)
		)
		(fp_text user "${REFERENCE}"
			(at -0.95 3.168 90)
			(layer "F.Fab")
			(effects
				(font
					(size 0.7 0.7)
					(thickness 0.15)
				)
				(justify left bottom)
			)
		)
		(fp_text user "Author: Antmicro"
			(at -0.95 4.169 90)
			(layer "F.Fab")
			(effects
				(font
					(size 0.7 0.7)
					(thickness 0.15)
				)
				(justify left bottom)
			)
		)
		(pad "1" smd roundrect
			(at -0.48 0 90)
			(size 0.59 0.64)
			(layers "F.Cu" "F.Mask" "F.Paste")
			(roundrect_rratio 0.25)
			(net 56 "/X710-AT2 10GbE/3V3_OSC")
			(pintype "passive")
		)
		(pad "2" smd roundrect
			(at 0.48 0 90)
			(size 0.59 0.64)
			(layers "F.Cu" "F.Mask" "F.Paste")
			(roundrect_rratio 0.25)
			(net 113 "/X710-AT2 10GbE/EN_OSC")
			(pintype "passive")
		)
	)
	(footprint "antmicro-footprints:C_0603_1608Metric_EIA"
		(layer "F.Cu")
		(at 142.799999 105.600003 90)
		(descr "Capacitor SMD 0603, IPC-7351 Density Level A")
		(tags "Capacitor 0603")
		(property "Reference" "C138"
			(at -17.849995 15.649999 90)
			(layer "F.SilkS")
			(effects
				(font
					(size 0.7 0.7)
					(thickness 0.15)
				)
			)
		)
		(property "Value" "C_22u_16V_0603"
			(at -1.42757 1.770288 90)
			(layer "F.Fab")
			(effects
				(font
					(size 0.7 0.7)
					(thickness 0.15)
				)
				(justify left bottom)
			)
		)
		(property "Datasheet" "https://product.samsungsem.com/mlcc/CL10A226MO7JZN.do"
			(at 0 0 90)
			(layer "F.Fab")
			(hide yes)
			(effects
				(font
					(size 1.27 1.27)
					(thickness 0.15)
				)
			)
		)
		(property "Description" "SMD Multilayer Ceramic Capacitor"
			(at 0 0 90)
			(layer "F.Fab")
			(hide yes)
			(effects
				(font
					(size 1.27 1.27)
					(thickness 0.15)
				)
			)
		)
		(property "MPN" "CL10A226MO7JZNC"
			(at 0 0 90)
			(unlocked yes)
			(layer "F.Fab")
			(hide yes)
			(effects
				(font
					(size 1 1)
					(thickness 0.15)
				)
			)
		)
		(property "Manufacturer" "Samsung Electro-Mechanics"
			(at 0 0 90)
			(unlocked yes)
			(layer "F.Fab")
			(hide yes)
			(effects
				(font
					(size 1 1)
					(thickness 0.15)
				)
			)
		)
		(property "License" "Apache-2.0"
			(at 0 0 90)
			(unlocked yes)
			(layer "F.Fab")
			(hide yes)
			(effects
				(font
					(size 1 1)
					(thickness 0.15)
				)
			)
		)
		(property "Author" "Antmicro"
			(at 0 0 90)
			(unlocked yes)
			(layer "F.Fab")
			(hide yes)
			(effects
				(font
					(size 1 1)
					(thickness 0.15)
				)
			)
		)
		(property "Val" "22u"
			(at 0 0 90)
			(unlocked yes)
			(layer "F.Fab")
			(hide yes)
			(effects
				(font
					(size 1 1)
					(thickness 0.15)
				)
			)
		)
		(property "Voltage" "16V"
			(at 0 0 90)
			(unlocked yes)
			(layer "F.Fab")
			(hide yes)
			(effects
				(font
					(size 1 1)
					(thickness 0.15)
				)
			)
		)
		(property "Dielectric" ""
			(at 0 0 90)
			(unlocked yes)
			(layer "F.Fab")
			(hide yes)
			(effects
				(font
					(size 1 1)
					(thickness 0.15)
				)
			)
		)
		(sheetname "/X710 DCDC converters/")
		(sheetfile "DCDC_converters_X710.kicad_sch")
		(attr smd)
		(fp_line
			(start -0.15 -0.55)
			(end 0.15 -0.55)
			(stroke
				(width 0.15)
				(type solid)
			)
			(layer "F.SilkS")
		)
		(fp_line
			(start -0.15 0.55)
			(end 0.15 0.55)
			(stroke
				(width 0.15)
				(type solid)
			)
			(layer "F.SilkS")
		)
		(fp_rect
			(start -1.25 -0.65)
			(end 1.25 0.65)
			(stroke
				(width 0.05)
				(type solid)
			)
			(fill no)
			(layer "F.CrtYd")
		)
		(fp_rect
			(start -0.8 -0.45)
			(end 0.8 0.45)
			(stroke
				(width 0.15)
				(type solid)
			)
			(fill no)
			(layer "F.Fab")
		)
		(fp_text user "License: Apache-2.0"
			(at -1.682 5.895 90)
			(layer "F.Fab")
			(effects
				(font
					(size 0.7 0.7)
					(thickness 0.15)
				)
				(justify left bottom)
			)
		)
		(fp_text user "${REFERENCE}"
			(at -1.682 3.895 90)
			(layer "F.Fab")
			(effects
				(font
					(size 0.7 0.7)
					(thickness 0.15)
				)
				(justify left bottom)
			)
		)
		(fp_text user "Author: Antmicro"
			(at -1.682 4.894 90)
			(layer "F.Fab")
			(effects
				(font
					(size 0.7 0.7)
					(thickness 0.15)
				)
				(justify left bottom)
			)
		)
		(pad "1" smd roundrect
			(at -0.7 0 90)
			(size 0.8 1.1)
			(layers "F.Cu" "F.Mask" "F.Paste")
			(roundrect_rratio 0.2)
			(net 23 "GND")
			(pintype "passive")
		)
		(pad "2" smd roundrect
			(at 0.7 0 90)
			(size 0.8 1.1)
			(layers "F.Cu" "F.Mask" "F.Paste")
			(roundrect_rratio 0.2)
			(net 341 "/X710 DCDC converters/+DVDD_OUT")
			(pintype "passive")
		)
	)
)
